# T6G (Grand Teton) — schematic netlist excerpt (pin names and nets, part order shuffled) for the footprints in the layout excerpt that follows; sources: Cadence DE-HDL packaged netlist, KiCad conversion of 04192023_DAF0TMB3IC0_F0TG_MB_C_brd_V02_OCP.brd

C6549  Q_CAP_DIFFBUS  DIFF BUS_0.22UF 6.3V 20% X6S  pkg C0201  page 286 : \1\ = P5E_CPU0_P1_TX_BUF_C_DP<8> ; \2\ = P5E_CPU0_P1_TX_BUF_DP<8>
C2268  Q_CAP  22UF 4V 20% X6S  pkg C0402  page 72 : A = PVDDCR_SOC_P1 ; B = GND

(kicad_pcb
	(version 20260206)
	(generator "pcbnew")
	(generator_version "10.0")
	(general
		(thickness 1.6)
		(legacy_teardrops no)
	)
	(paper "A4")
	(title_block
		(title "04192023_DAF0TMB3IC0_F0TG_MB_C_brd_V02_OCP.brd")
		(comment 1 "Grand Teton / footprints 6184-6185 of 8354")
	)
	(layers
		(0 "F.Cu" signal "TOP")
		(4 "In1.Cu" signal "GND")
		(6 "In2.Cu" signal "IN1")
		(8 "In3.Cu" signal "GND1")
		(10 "In4.Cu" signal "IN2")
		(12 "In5.Cu" signal "GND2")
		(14 "In6.Cu" signal "IN3")
		(16 "In7.Cu" signal "GND3")
		(18 "In8.Cu" signal "VCC")
		(20 "In9.Cu" signal "VCC1")
		(22 "In10.Cu" signal "GND4")
		(24 "In11.Cu" signal "IN4")
		(26 "In12.Cu" signal "GND5")
		(28 "In13.Cu" signal "IN5")
		(30 "In14.Cu" signal "GND6")
		(32 "In15.Cu" signal "IN6")
		(34 "In16.Cu" signal "GND7")
		(2 "B.Cu" signal "BOTTOM")
		(9 "F.Adhes" user "F.Adhesive")
		(11 "B.Adhes" user "B.Adhesive")
		(13 "F.Paste" user "Package Geometry/Pastemask Top")
		(15 "B.Paste" user "Package Geometry/Pastemask Bottom")
		(5 "F.SilkS" user "Ref Des/Silkscreen Top")
		(7 "B.SilkS" user "Ref Des/Silkscreen Bottom")
		(1 "F.Mask" user "Board Geometry/Soldermask Top")
		(3 "B.Mask" user "Board Geometry/Soldermask Bottom")
		(17 "Dwgs.User" user "User.Drawings")
		(19 "Cmts.User" user "User.Comments")
		(21 "Eco1.User" user "User.Eco1")
		(23 "Eco2.User" user "User.Eco2")
		(25 "Edge.Cuts" user "Board Geometry/Outline")
		(27 "Margin" user)
		(31 "F.CrtYd" user "Package Geometry/Place Bound Top")
		(29 "B.CrtYd" user "Package Geometry/Place Bound Bottom")
		(35 "F.Fab" user "Ref Des/Assembly Top")
		(33 "B.Fab" user "Ref Des/Assembly Bottom")
	)
	(footprint ""
		(layer "B.Cu")
		(at 111.781336 -252.416564 180)
		(property "Reference" "C2268"
			(at 0 0 0)
			(layer "B.SilkS")
			(hide yes)
			(effects
				(font
					(size 1.27 1.27)
				)
				(justify mirror)
			)
		)
		(property "Value" ""
			(at 0 0 0)
			(layer "B.Fab")
			(effects
				(font
					(size 1.27 1.27)
				)
				(justify mirror)
			)
		)
		(duplicate_pad_numbers_are_jumpers no)
		(fp_line
			(start 0.7874 0.4064)
			(end 0.7874 -0.4064)
			(stroke
				(width 0.1524)
				(type default)
			)
			(layer "B.SilkS")
		)
		(fp_line
			(start 0.7874 -0.4064)
			(end -0.7874 -0.4064)
			(stroke
				(width 0.1524)
				(type default)
			)
			(layer "B.SilkS")
		)
		(fp_line
			(start -0.7874 0.4064)
			(end 0.7874 0.4064)
			(stroke
				(width 0.1524)
				(type default)
			)
			(layer "B.SilkS")
		)
		(fp_line
			(start -0.7874 -0.4064)
			(end -0.7874 0.4064)
			(stroke
				(width 0.1524)
				(type default)
			)
			(layer "B.SilkS")
		)
		(fp_line
			(start 0.67945 0.3048)
			(end 0.67945 -0.305054)
			(stroke
				(width 0.1)
				(type default)
			)
			(layer "B.Fab")
		)
		(fp_line
			(start 0.67945 -0.305054)
			(end 0.12065 -0.305054)
			(stroke
				(width 0.1)
				(type default)
			)
			(layer "B.Fab")
		)
		(fp_line
			(start 0.12065 0.3048)
			(end 0.67945 0.3048)
			(stroke
				(width 0.1)
				(type default)
			)
			(layer "B.Fab")
		)
		(fp_line
			(start 0.12065 0.2794)
			(end 0.12065 0.3048)
			(stroke
				(width 0.1)
				(type default)
			)
			(layer "B.Fab")
		)
		(fp_line
			(start 0.12065 -0.2794)
			(end -0.12065 -0.2794)
			(stroke
				(width 0.1)
				(type default)
			)
			(layer "B.Fab")
		)
		(fp_line
			(start 0.12065 -0.305054)
			(end 0.12065 -0.2794)
			(stroke
				(width 0.1)
				(type default)
			)
			(layer "B.Fab")
		)
		(fp_line
			(start -0.120396 0.3048)
			(end -0.120396 0.2794)
			(stroke
				(width 0.1)
				(type default)
			)
			(layer "B.Fab")
		)
		(fp_line
			(start -0.120396 0.2794)
			(end 0.12065 0.2794)
			(stroke
				(width 0.1)
				(type default)
			)
			(layer "B.Fab")
		)
		(fp_line
			(start -0.12065 -0.2794)
			(end -0.12065 -0.3048)
			(stroke
				(width 0.1)
				(type default)
			)
			(layer "B.Fab")
		)
		(fp_line
			(start -0.12065 -0.3048)
			(end -0.67945 -0.3048)
			(stroke
				(width 0.1)
				(type default)
			)
			(layer "B.Fab")
		)
		(fp_line
			(start -0.67945 0.3048)
			(end -0.120396 0.3048)
			(stroke
				(width 0.1)
				(type default)
			)
			(layer "B.Fab")
		)
		(fp_line
			(start -0.67945 -0.3048)
			(end -0.67945 0.3048)
			(stroke
				(width 0.1)
				(type default)
			)
			(layer "B.Fab")
		)
		(pad "1" smd circle
			(at 0.40005 0)
			(size 0 0)
			(layers "B.Cu" "B.Mask" "B.Paste")
			(net "PVDDCR_SOC_P1")
		)
		(pad "2" smd circle
			(at -0.40005 0)
			(size 0 0)
			(layers "B.Cu" "B.Mask" "B.Paste")
			(net "GND")
		)
	)
	(footprint ""
		(layer "B.Cu")
		(at 330.720446 -416.899344 90)
		(property "Reference" "C6549"
			(at 0 0 90)
			(layer "B.SilkS")
			(hide yes)
			(effects
				(font
					(size 1.27 1.27)
				)
				(justify mirror)
			)
		)
		(property "Value" ""
			(at 0 0 90)
			(layer "B.Fab")
			(effects
				(font
					(size 1.27 1.27)
				)
				(justify mirror)
			)
		)
		(duplicate_pad_numbers_are_jumpers no)
		(fp_line
			(start 0.299974 -0.150114)
			(end -0.299974 -0.150114)
			(stroke
				(width 0.1)
				(type default)
			)
			(layer "B.Fab")
		)
		(fp_line
			(start -0.299974 -0.150114)
			(end -0.299974 0.150114)
			(stroke
				(width 0.1)
				(type default)
			)
			(layer "B.Fab")
		)
		(fp_line
			(start 0.299974 0.150114)
			(end 0.299974 -0.150114)
			(stroke
				(width 0.1)
				(type default)
			)
			(layer "B.Fab")
		)
		(fp_line
			(start -0.299974 0.150114)
			(end 0.299974 0.150114)
			(stroke
				(width 0.1)
				(type default)
			)
			(layer "B.Fab")
		)
		(pad "1" smd rect
			(at 0.2667 0 270)
			(size 0.3048 0.381)
			(layers "B.Cu" "B.Mask" "B.Paste")
			(net "P5E_CPU0_P1_TX_BUF_C_DP<8>")
		)
		(pad "2" smd rect
			(at -0.2667 0 270)
			(size 0.3048 0.381)
			(layers "B.Cu" "B.Mask" "B.Paste")
			(net "P5E_CPU0_P1_TX_BUF_DP<8>")
		)
	)
)
